(kicad_pcb
	(version 20260206)
	(generator "pcbnew")
	(generator_version "10.0")
	(general
		(thickness 1.6)
		(legacy_teardrops no)
	)
	(paper "A4")
	(title_block
		(title "03242023_DA0F0TMBIJ0_F0T_Motherboard_J_brd_V01_OCP.brd")
		(comment 1 "Grand Teton / footprints 3103-3109 of 6105")
	)
	(layers
		(0 "F.Cu" signal "TOP")
		(4 "In1.Cu" signal "GND")
		(6 "In2.Cu" signal "IN1")
		(8 "In3.Cu" signal "GND1")
		(10 "In4.Cu" signal "IN2")
		(12 "In5.Cu" signal "GND2")
		(14 "In6.Cu" signal "IN3")
		(16 "In7.Cu" signal "GND3")
		(18 "In8.Cu" signal "VCC")
		(20 "In9.Cu" signal "VCC1")
		(22 "In10.Cu" signal "GND4")
		(24 "In11.Cu" signal "IN4")
		(26 "In12.Cu" signal "GND5")
		(28 "In13.Cu" signal "IN5")
		(30 "In14.Cu" signal "GND6")
		(32 "In15.Cu" signal "IN6")
		(34 "In16.Cu" signal "GND7")
		(2 "B.Cu" signal "BOTTOM")
		(9 "F.Adhes" user "F.Adhesive")
		(11 "B.Adhes" user "B.Adhesive")
		(13 "F.Paste" user "Package Geometry/Pastemask Top")
		(15 "B.Paste" user "Package Geometry/Pastemask Bottom")
		(5 "F.SilkS" user "Ref Des/Silkscreen Top")
		(7 "B.SilkS" user "Ref Des/Silkscreen Bottom")
		(1 "F.Mask" user "Board Geometry/Soldermask Top")
		(3 "B.Mask" user "Board Geometry/Soldermask Bottom")
		(17 "Dwgs.User" user "User.Drawings")
		(19 "Cmts.User" user "User.Comments")
		(21 "Eco1.User" user "User.Eco1")
		(23 "Eco2.User" user "User.Eco2")
		(25 "Edge.Cuts" user "Board Geometry/Outline")
		(27 "Margin" user)
		(31 "F.CrtYd" user "Package Geometry/Place Bound Top")
		(29 "B.CrtYd" user "Package Geometry/Place Bound Bottom")
		(35 "F.Fab" user "Ref Des/Assembly Top")
		(33 "B.Fab" user "Ref Des/Assembly Bottom")
	)
	(footprint ""
		(layer "F.Cu")
		(at 438.920636 -46.033436 180)
		(property "Reference" "C1860"
			(at 0 0 180)
			(layer "F.SilkS")
			(hide yes)
			(effects
				(font
					(size 1.27 1.27)
				)
			)
		)
		(property "Value" ""
			(at 0 0 180)
			(layer "F.Fab")
			(effects
				(font
					(size 1.27 1.27)
				)
			)
		)
		(duplicate_pad_numbers_are_jumpers no)
		(fp_line
			(start 0.7874 0.4064)
			(end -0.7874 0.4064)
			(stroke
				(width 0.1524)
				(type default)
			)
			(layer "F.SilkS")
		)
		(fp_line
			(start 0.7874 -0.4064)
			(end 0.7874 0.4064)
			(stroke
				(width 0.1524)
				(type default)
			)
			(layer "F.SilkS")
		)
		(fp_line
			(start -0.7874 0.4064)
			(end -0.7874 -0.4064)
			(stroke
				(width 0.1524)
				(type default)
			)
			(layer "F.SilkS")
		)
		(fp_line
			(start -0.7874 -0.4064)
			(end 0.7874 -0.4064)
			(stroke
				(width 0.1524)
				(type default)
			)
			(layer "F.SilkS")
		)
		(fp_line
			(start 0.67945 0.3048)
			(end 0.120396 0.3048)
			(stroke
				(width 0.1)
				(type default)
			)
			(layer "F.Fab")
		)
		(fp_line
			(start 0.67945 -0.3048)
			(end 0.67945 0.3048)
			(stroke
				(width 0.1)
				(type default)
			)
			(layer "F.Fab")
		)
		(fp_line
			(start 0.12065 -0.2794)
			(end 0.12065 -0.3048)
			(stroke
				(width 0.1)
				(type default)
			)
			(layer "F.Fab")
		)
		(fp_line
			(start 0.12065 -0.3048)
			(end 0.67945 -0.3048)
			(stroke
				(width 0.1)
				(type default)
			)
			(layer "F.Fab")
		)
		(fp_line
			(start 0.120396 0.3048)
			(end 0.120396 0.2794)
			(stroke
				(width 0.1)
				(type default)
			)
			(layer "F.Fab")
		)
		(fp_line
			(start 0.120396 0.2794)
			(end -0.12065 0.2794)
			(stroke
				(width 0.1)
				(type default)
			)
			(layer "F.Fab")
		)
		(fp_line
			(start -0.12065 0.3048)
			(end -0.67945 0.3048)
			(stroke
				(width 0.1)
				(type default)
			)
			(layer "F.Fab")
		)
		(fp_line
			(start -0.12065 0.2794)
			(end -0.12065 0.3048)
			(stroke
				(width 0.1)
				(type default)
			)
			(layer "F.Fab")
		)
		(fp_line
			(start -0.12065 -0.2794)
			(end 0.12065 -0.2794)
			(stroke
				(width 0.1)
				(type default)
			)
			(layer "F.Fab")
		)
		(fp_line
			(start -0.12065 -0.305054)
			(end -0.12065 -0.2794)
			(stroke
				(width 0.1)
				(type default)
			)
			(layer "F.Fab")
		)
		(fp_line
			(start -0.67945 0.3048)
			(end -0.67945 -0.305054)
			(stroke
				(width 0.1)
				(type default)
			)
			(layer "F.Fab")
		)
		(fp_line
			(start -0.67945 -0.305054)
			(end -0.12065 -0.305054)
			(stroke
				(width 0.1)
				(type default)
			)
			(layer "F.Fab")
		)
		(pad "1" smd circle
			(at -0.40005 0 180)
			(size 0 0)
			(layers "F.Cu" "F.Mask" "F.Paste")
			(net "P3V3_AUX")
		)
		(pad "2" smd circle
			(at 0.40005 0 180)
			(size 0 0)
			(layers "F.Cu" "F.Mask" "F.Paste")
			(net "GND")
		)
	)
	(footprint ""
		(layer "F.Cu")
		(at 168.96588 -436.971948)
		(property "Reference" "C1958"
			(at 0 0 0)
			(layer "F.SilkS")
			(hide yes)
			(effects
				(font
					(size 1.27 1.27)
				)
			)
		)
		(property "Value" ""
			(at 0 0 0)
			(layer "F.Fab")
			(effects
				(font
					(size 1.27 1.27)
				)
			)
		)
		(duplicate_pad_numbers_are_jumpers no)
		(fp_line
			(start -0.7874 -0.4064)
			(end 0.7874 -0.4064)
			(stroke
				(width 0.1524)
				(type default)
			)
			(layer "F.SilkS")
		)
		(fp_line
			(start -0.7874 0.4064)
			(end -0.7874 -0.4064)
			(stroke
				(width 0.1524)
				(type default)
			)
			(layer "F.SilkS")
		)
		(fp_line
			(start 0.7874 -0.4064)
			(end 0.7874 0.4064)
			(stroke
				(width 0.1524)
				(type default)
			)
			(layer "F.SilkS")
		)
		(fp_line
			(start 0.7874 0.4064)
			(end -0.7874 0.4064)
			(stroke
				(width 0.1524)
				(type default)
			)
			(layer "F.SilkS")
		)
		(fp_line
			(start -0.67945 -0.305054)
			(end -0.12065 -0.305054)
			(stroke
				(width 0.1)
				(type default)
			)
			(layer "F.Fab")
		)
		(fp_line
			(start -0.67945 0.3048)
			(end -0.67945 -0.305054)
			(stroke
				(width 0.1)
				(type default)
			)
			(layer "F.Fab")
		)
		(fp_line
			(start -0.12065 -0.305054)
			(end -0.12065 -0.2794)
			(stroke
				(width 0.1)
				(type default)
			)
			(layer "F.Fab")
		)
		(fp_line
			(start -0.12065 -0.2794)
			(end 0.12065 -0.2794)
			(stroke
				(width 0.1)
				(type default)
			)
			(layer "F.Fab")
		)
		(fp_line
			(start -0.12065 0.2794)
			(end -0.12065 0.3048)
			(stroke
				(width 0.1)
				(type default)
			)
			(layer "F.Fab")
		)
		(fp_line
			(start -0.12065 0.3048)
			(end -0.67945 0.3048)
			(stroke
				(width 0.1)
				(type default)
			)
			(layer "F.Fab")
		)
		(fp_line
			(start 0.120396 0.2794)
			(end -0.12065 0.2794)
			(stroke
				(width 0.1)
				(type default)
			)
			(layer "F.Fab")
		)
		(fp_line
			(start 0.120396 0.3048)
			(end 0.120396 0.2794)
			(stroke
				(width 0.1)
				(type default)
			)
			(layer "F.Fab")
		)
		(fp_line
			(start 0.12065 -0.3048)
			(end 0.67945 -0.3048)
			(stroke
				(width 0.1)
				(type default)
			)
			(layer "F.Fab")
		)
		(fp_line
			(start 0.12065 -0.2794)
			(end 0.12065 -0.3048)
			(stroke
				(width 0.1)
				(type default)
			)
			(layer "F.Fab")
		)
		(fp_line
			(start 0.67945 -0.3048)
			(end 0.67945 0.3048)
			(stroke
				(width 0.1)
				(type default)
			)
			(layer "F.Fab")
		)
		(fp_line
			(start 0.67945 0.3048)
			(end 0.120396 0.3048)
			(stroke
				(width 0.1)
				(type default)
			)
			(layer "F.Fab")
		)
		(pad "1" smd circle
			(at -0.40005 0)
			(size 0 0)
			(layers "F.Cu" "F.Mask" "F.Paste")
			(net "P3V3_AUX")
		)
		(pad "2" smd circle
			(at 0.40005 0)
			(size 0 0)
			(layers "F.Cu" "F.Mask" "F.Paste")
			(net "GND")
		)
	)
	(footprint ""
		(layer "F.Cu")
		(at 434.113178 -183.84139 90)
		(property "Reference" "PR1301"
			(at 0 0 90)
			(layer "F.SilkS")
			(hide yes)
			(effects
				(font
					(size 1.27 1.27)
				)
			)
		)
		(property "Value" ""
			(at 0 0 90)
			(layer "F.Fab")
			(effects
				(font
					(size 1.27 1.27)
				)
			)
		)
		(duplicate_pad_numbers_are_jumpers no)
		(fp_line
			(start 0.7874 -0.4064)
			(end 0.7874 0.4064)
			(stroke
				(width 0.1524)
				(type default)
			)
			(layer "F.SilkS")
		)
		(fp_line
			(start -0.7874 -0.4064)
			(end 0.7874 -0.4064)
			(stroke
				(width 0.1524)
				(type default)
			)
			(layer "F.SilkS")
		)
		(fp_line
			(start 0.7874 0.4064)
			(end -0.7874 0.4064)
			(stroke
				(width 0.1524)
				(type default)
			)
			(layer "F.SilkS")
		)
		(fp_line
			(start -0.7874 0.4064)
			(end -0.7874 -0.4064)
			(stroke
				(width 0.1524)
				(type default)
			)
			(layer "F.SilkS")
		)
		(fp_line
			(start -0.12065 -0.305054)
			(end -0.12065 -0.2794)
			(stroke
				(width 0.1)
				(type default)
			)
			(layer "F.Fab")
		)
		(fp_line
			(start -0.67945 -0.305054)
			(end -0.12065 -0.305054)
			(stroke
				(width 0.1)
				(type default)
			)
			(layer "F.Fab")
		)
		(fp_line
			(start 0.67945 -0.3048)
			(end 0.67945 0.3048)
			(stroke
				(width 0.1)
				(type default)
			)
			(layer "F.Fab")
		)
		(fp_line
			(start 0.12065 -0.3048)
			(end 0.67945 -0.3048)
			(stroke
				(width 0.1)
				(type default)
			)
			(layer "F.Fab")
		)
		(fp_line
			(start 0.12065 -0.2794)
			(end 0.12065 -0.3048)
			(stroke
				(width 0.1)
				(type default)
			)
			(layer "F.Fab")
		)
		(fp_line
			(start -0.12065 -0.2794)
			(end 0.12065 -0.2794)
			(stroke
				(width 0.1)
				(type default)
			)
			(layer "F.Fab")
		)
		(fp_line
			(start 0.120396 0.2794)
			(end -0.12065 0.2794)
			(stroke
				(width 0.1)
				(type default)
			)
			(layer "F.Fab")
		)
		(fp_line
			(start -0.12065 0.2794)
			(end -0.12065 0.3048)
			(stroke
				(width 0.1)
				(type default)
			)
			(layer "F.Fab")
		)
		(fp_line
			(start 0.67945 0.3048)
			(end 0.120396 0.3048)
			(stroke
				(width 0.1)
				(type default)
			)
			(layer "F.Fab")
		)
		(fp_line
			(start 0.120396 0.3048)
			(end 0.120396 0.2794)
			(stroke
				(width 0.1)
				(type default)
			)
			(layer "F.Fab")
		)
		(fp_line
			(start -0.12065 0.3048)
			(end -0.67945 0.3048)
			(stroke
				(width 0.1)
				(type default)
			)
			(layer "F.Fab")
		)
		(fp_line
			(start -0.67945 0.3048)
			(end -0.67945 -0.305054)
			(stroke
				(width 0.1)
				(type default)
			)
			(layer "F.Fab")
		)
		(pad "1" smd circle
			(at -0.40005 0 90)
			(size 0 0)
			(layers "F.Cu" "F.Mask" "F.Paste")
			(net "PVNN_MAIN_CPU0_MODE")
		)
		(pad "2" smd circle
			(at 0.40005 0 90)
			(size 0 0)
			(layers "F.Cu" "F.Mask" "F.Paste")
			(net "GND")
		)
	)
	(footprint ""
		(layer "F.Cu")
		(at 457.52131 -42.05351)
		(property "Reference" "R5487"
			(at 0 0 0)
			(layer "F.SilkS")
			(hide yes)
			(effects
				(font
					(size 1.27 1.27)
				)
			)
		)
		(property "Value" ""
			(at 0 0 0)
			(layer "F.Fab")
			(effects
				(font
					(size 1.27 1.27)
				)
			)
		)
		(duplicate_pad_numbers_are_jumpers no)
		(fp_line
			(start -0.7874 -0.4064)
			(end 0.7874 -0.4064)
			(stroke
				(width 0.1524)
				(type default)
			)
			(layer "F.SilkS")
		)
		(fp_line
			(start -0.7874 0.4064)
			(end -0.7874 -0.4064)
			(stroke
				(width 0.1524)
				(type default)
			)
			(layer "F.SilkS")
		)
		(fp_line
			(start 0.7874 -0.4064)
			(end 0.7874 0.4064)
			(stroke
				(width 0.1524)
				(type default)
			)
			(layer "F.SilkS")
		)
		(fp_line
			(start 0.7874 0.4064)
			(end -0.7874 0.4064)
			(stroke
				(width 0.1524)
				(type default)
			)
			(layer "F.SilkS")
		)
		(fp_line
			(start -0.67945 -0.305054)
			(end -0.12065 -0.305054)
			(stroke
				(width 0.1)
				(type default)
			)
			(layer "F.Fab")
		)
		(fp_line
			(start -0.67945 0.3048)
			(end -0.67945 -0.305054)
			(stroke
				(width 0.1)
				(type default)
			)
			(layer "F.Fab")
		)
		(fp_line
			(start -0.12065 -0.305054)
			(end -0.12065 -0.2794)
			(stroke
				(width 0.1)
				(type default)
			)
			(layer "F.Fab")
		)
		(fp_line
			(start -0.12065 -0.2794)
			(end 0.12065 -0.2794)
			(stroke
				(width 0.1)
				(type default)
			)
			(layer "F.Fab")
		)
		(fp_line
			(start -0.12065 0.2794)
			(end -0.12065 0.3048)
			(stroke
				(width 0.1)
				(type default)
			)
			(layer "F.Fab")
		)
		(fp_line
			(start -0.12065 0.3048)
			(end -0.67945 0.3048)
			(stroke
				(width 0.1)
				(type default)
			)
			(layer "F.Fab")
		)
		(fp_line
			(start 0.120396 0.2794)
			(end -0.12065 0.2794)
			(stroke
				(width 0.1)
				(type default)
			)
			(layer "F.Fab")
		)
		(fp_line
			(start 0.120396 0.3048)
			(end 0.120396 0.2794)
			(stroke
				(width 0.1)
				(type default)
			)
			(layer "F.Fab")
		)
		(fp_line
			(start 0.12065 -0.3048)
			(end 0.67945 -0.3048)
			(stroke
				(width 0.1)
				(type default)
			)
			(layer "F.Fab")
		)
		(fp_line
			(start 0.12065 -0.2794)
			(end 0.12065 -0.3048)
			(stroke
				(width 0.1)
				(type default)
			)
			(layer "F.Fab")
		)
		(fp_line
			(start 0.67945 -0.3048)
			(end 0.67945 0.3048)
			(stroke
				(width 0.1)
				(type default)
			)
			(layer "F.Fab")
		)
		(fp_line
			(start 0.67945 0.3048)
			(end 0.120396 0.3048)
			(stroke
				(width 0.1)
				(type default)
			)
			(layer "F.Fab")
		)
		(pad "1" smd circle
			(at -0.40005 0)
			(size 0 0)
			(layers "F.Cu" "F.Mask" "F.Paste")
			(net "HP_LVC3_OCP_V3_1_EN")
		)
		(pad "2" smd circle
			(at 0.40005 0)
			(size 0 0)
			(layers "F.Cu" "F.Mask" "F.Paste")
			(net "P3V3_OCP_EN_1_R")
		)
	)
	(footprint ""
		(layer "F.Cu")
		(at 463.465926 -96.406208)
		(property "Reference" "R2474"
			(at 0 0 0)
			(layer "F.SilkS")
			(hide yes)
			(effects
				(font
					(size 1.27 1.27)
				)
			)
		)
		(property "Value" ""
			(at 0 0 0)
			(layer "F.Fab")
			(effects
				(font
					(size 1.27 1.27)
				)
			)
		)
		(duplicate_pad_numbers_are_jumpers no)
		(fp_line
			(start -0.7874 -0.4064)
			(end 0.7874 -0.4064)
			(stroke
				(width 0.1524)
				(type default)
			)
			(layer "F.SilkS")
		)
		(fp_line
			(start -0.7874 0.4064)
			(end -0.7874 -0.4064)
			(stroke
				(width 0.1524)
				(type default)
			)
			(layer "F.SilkS")
		)
		(fp_line
			(start 0.7874 -0.4064)
			(end 0.7874 0.4064)
			(stroke
				(width 0.1524)
				(type default)
			)
			(layer "F.SilkS")
		)
		(fp_line
			(start 0.7874 0.4064)
			(end -0.7874 0.4064)
			(stroke
				(width 0.1524)
				(type default)
			)
			(layer "F.SilkS")
		)
		(fp_line
			(start -0.67945 -0.305054)
			(end -0.12065 -0.305054)
			(stroke
				(width 0.1)
				(type default)
			)
			(layer "F.Fab")
		)
		(fp_line
			(start -0.67945 0.3048)
			(end -0.67945 -0.305054)
			(stroke
				(width 0.1)
				(type default)
			)
			(layer "F.Fab")
		)
		(fp_line
			(start -0.12065 -0.305054)
			(end -0.12065 -0.2794)
			(stroke
				(width 0.1)
				(type default)
			)
			(layer "F.Fab")
		)
		(fp_line
			(start -0.12065 -0.2794)
			(end 0.12065 -0.2794)
			(stroke
				(width 0.1)
				(type default)
			)
			(layer "F.Fab")
		)
		(fp_line
			(start -0.12065 0.2794)
			(end -0.12065 0.3048)
			(stroke
				(width 0.1)
				(type default)
			)
			(layer "F.Fab")
		)
		(fp_line
			(start -0.12065 0.3048)
			(end -0.67945 0.3048)
			(stroke
				(width 0.1)
				(type default)
			)
			(layer "F.Fab")
		)
		(fp_line
			(start 0.120396 0.2794)
			(end -0.12065 0.2794)
			(stroke
				(width 0.1)
				(type default)
			)
			(layer "F.Fab")
		)
		(fp_line
			(start 0.120396 0.3048)
			(end 0.120396 0.2794)
			(stroke
				(width 0.1)
				(type default)
			)
			(layer "F.Fab")
		)
		(fp_line
			(start 0.12065 -0.3048)
			(end 0.67945 -0.3048)
			(stroke
				(width 0.1)
				(type default)
			)
			(layer "F.Fab")
		)
		(fp_line
			(start 0.12065 -0.2794)
			(end 0.12065 -0.3048)
			(stroke
				(width 0.1)
				(type default)
			)
			(layer "F.Fab")
		)
		(fp_line
			(start 0.67945 -0.3048)
			(end 0.67945 0.3048)
			(stroke
				(width 0.1)
				(type default)
			)
			(layer "F.Fab")
		)
		(fp_line
			(start 0.67945 0.3048)
			(end 0.120396 0.3048)
			(stroke
				(width 0.1)
				(type default)
			)
			(layer "F.Fab")
		)
		(pad "1" smd circle
			(at -0.40005 0)
			(size 0 0)
			(layers "F.Cu" "F.Mask" "F.Paste")
			(net "FM_NCSI_OCP_V3_1_R_OE")
		)
		(pad "2" smd circle
			(at 0.40005 0)
			(size 0 0)
			(layers "F.Cu" "F.Mask" "F.Paste")
			(net "FB_BMC_ISOLATE")
		)
	)
	(footprint ""
		(layer "F.Cu")
		(at 212.598 -113.4872)
		(property "Reference" "C2384"
			(at 0 0 0)
			(layer "F.SilkS")
			(hide yes)
			(effects
				(font
					(size 1.27 1.27)
				)
			)
		)
		(property "Value" ""
			(at 0 0 0)
			(layer "F.Fab")
			(effects
				(font
					(size 1.27 1.27)
				)
			)
		)
		(duplicate_pad_numbers_are_jumpers no)
		(fp_line
			(start -0.7874 -0.4064)
			(end 0.7874 -0.4064)
			(stroke
				(width 0.1524)
				(type default)
			)
			(layer "F.SilkS")
		)
		(fp_line
			(start -0.7874 0.4064)
			(end -0.7874 -0.4064)
			(stroke
				(width 0.1524)
				(type default)
			)
			(layer "F.SilkS")
		)
		(fp_line
			(start 0.7874 -0.4064)
			(end 0.7874 0.4064)
			(stroke
				(width 0.1524)
				(type default)
			)
			(layer "F.SilkS")
		)
		(fp_line
			(start 0.7874 0.4064)
			(end -0.7874 0.4064)
			(stroke
				(width 0.1524)
				(type default)
			)
			(layer "F.SilkS")
		)
		(fp_line
			(start -0.67945 -0.305054)
			(end -0.12065 -0.305054)
			(stroke
				(width 0.1)
				(type default)
			)
			(layer "F.Fab")
		)
		(fp_line
			(start -0.67945 0.3048)
			(end -0.67945 -0.305054)
			(stroke
				(width 0.1)
				(type default)
			)
			(layer "F.Fab")
		)
		(fp_line
			(start -0.12065 -0.305054)
			(end -0.12065 -0.2794)
			(stroke
				(width 0.1)
				(type default)
			)
			(layer "F.Fab")
		)
		(fp_line
			(start -0.12065 -0.2794)
			(end 0.12065 -0.2794)
			(stroke
				(width 0.1)
				(type default)
			)
			(layer "F.Fab")
		)
		(fp_line
			(start -0.12065 0.2794)
			(end -0.12065 0.3048)
			(stroke
				(width 0.1)
				(type default)
			)
			(layer "F.Fab")
		)
		(fp_line
			(start -0.12065 0.3048)
			(end -0.67945 0.3048)
			(stroke
				(width 0.1)
				(type default)
			)
			(layer "F.Fab")
		)
		(fp_line
			(start 0.120396 0.2794)
			(end -0.12065 0.2794)
			(stroke
				(width 0.1)
				(type default)
			)
			(layer "F.Fab")
		)
		(fp_line
			(start 0.120396 0.3048)
			(end 0.120396 0.2794)
			(stroke
				(width 0.1)
				(type default)
			)
			(layer "F.Fab")
		)
		(fp_line
			(start 0.12065 -0.3048)
			(end 0.67945 -0.3048)
			(stroke
				(width 0.1)
				(type default)
			)
			(layer "F.Fab")
		)
		(fp_line
			(start 0.12065 -0.2794)
			(end 0.12065 -0.3048)
			(stroke
				(width 0.1)
				(type default)
			)
			(layer "F.Fab")
		)
		(fp_line
			(start 0.67945 -0.3048)
			(end 0.67945 0.3048)
			(stroke
				(width 0.1)
				(type default)
			)
			(layer "F.Fab")
		)
		(fp_line
			(start 0.67945 0.3048)
			(end 0.120396 0.3048)
			(stroke
				(width 0.1)
				(type default)
			)
			(layer "F.Fab")
		)
		(pad "1" smd circle
			(at -0.40005 0)
			(size 0 0)
			(layers "F.Cu" "F.Mask" "F.Paste")
			(net "P12V_AUX")
		)
		(pad "2" smd circle
			(at 0.40005 0)
			(size 0 0)
			(layers "F.Cu" "F.Mask" "F.Paste")
			(net "GND")
		)
	)
	(footprint ""
		(layer "F.Cu")
		(at 93.903038 -402.371052 -90)
		(property "Reference" "C740"
			(at 0 0 270)
			(layer "F.SilkS")
			(hide yes)
			(effects
				(font
					(size 1.27 1.27)
				)
			)
		)
		(property "Value" ""
			(at 0 0 270)
			(layer "F.Fab")
			(effects
				(font
					(size 1.27 1.27)
				)
			)
		)
		(duplicate_pad_numbers_are_jumpers no)
		(fp_line
			(start -0.299974 0.150114)
			(end -0.299974 -0.150114)
			(stroke
				(width 0.1)
				(type default)
			)
			(layer "F.Fab")
		)
		(fp_line
			(start 0.299974 0.150114)
			(end -0.299974 0.150114)
			(stroke
				(width 0.1)
				(type default)
			)
			(layer "F.Fab")
		)
		(fp_line
			(start -0.299974 -0.150114)
			(end 0.299974 -0.150114)
			(stroke
				(width 0.1)
				(type default)
			)
			(layer "F.Fab")
		)
		(fp_line
			(start 0.299974 -0.150114)
			(end 0.299974 0.150114)
			(stroke
				(width 0.1)
				(type default)
			)
			(layer "F.Fab")
		)
		(pad "1" smd rect
			(at -0.2667 0 270)
			(size 0.3048 0.381)
			(layers "F.Cu" "F.Mask" "F.Paste")
			(net "P5E_CPU1_PE0_TX_C_DN<0>")
		)
		(pad "2" smd rect
			(at 0.2667 0 270)
			(size 0.3048 0.381)
			(layers "F.Cu" "F.Mask" "F.Paste")
			(net "P5E_CPU1_PE0_TX_DN<0>")
		)
	)
)
